FILE_TYPE = CONNECTIVITY;
{Allegro Design Entry HDL 16.6-p007 (v16-6-112F) 10/10/2012}
"PAGE_NUMBER" = 154;
0"NC";
1"GND\g";
2"P3V3_STBY\g";
3"P3V3_STBY\g";
4"P3V3_STBY\g";
5"GND\g";
6"GND\g";
7"P3V3_STBY\g";
8"GND\g";
9"P3V3_STBY\g";
10"GND\g";
11"P3V3_STBY\g";
12"GND\g";
13"GND\g";
14"GND\g";
15"P3V3_STBY\g";
16"GND\g";
17"GND\g";
18"SPI_BMC_DO";
19"SPI_PCH_CS0_N";
20"SPI_PCH_MOSI";
21"SPI_BMC_BT_CS1_N";
22"SPI_BMC_DI";
23"SPI_PCH_MISO";
24"FM_BIOS_SPI_BMC_CTRL";
25"SPI_PCH_CLK";
26"SPI_BMC_CLK";
27"FM_BIOS_SPI_BMC_CTRL";
28"SPI_BIOS_SOCKET_IO2";
29"SPI_BIOS_SOCKET_IO3";
30"TP_SPI_SWITCH1_9";
31"SPI_SWITCH_CS0_N";
32"FM_BACKUP_BIOS_SEL_N";
33"SPI_PCH_MISO_R";
34"SPI_PCH_IO3_R1";
35"TP_SPI_SWITCH1_11";
36"TP_SPI_SWITCH1_10";
37"TP_SPI_SWITCH1_14";
38"TP_SPI_SWITCH1_13";
39"SPI_PCH_IO3";
40"SPI_PCH_IO2";
41"FM_BIOS_SPI_BMC_CTRL";
42"SPI_SWITCH_CLK";
43"SPI_SWITCH_MOSI";
44"SPI_SWITCH_CS0_N";
45"SPI_SWITCH_MISO";
46"FM_DUAL_BIOS_SEL_N";
47"TP_SPI_SWITCH1_3";
48"SPI_PCH_IO2_R1";
49"TP_SPI_SWITCH1_6";
50"SPI_CS0_SECONDARY_N";
51"SPI_CS0_PRIMARY_N";
52"SPI_CS0_PRIMARY_R_N";
53"SPI_CS0_SECONDARY_R_N";
54"TP_SPI_SWITCH1_12";
%"TTL1G32_A"
"1","(-2275,1150)","0","mstr_ttl","I100";
;
CDS_SEC"1"
PACK_TYPE"SOT"
CDS_LIB"mstr_ttl"
SEC_TYPE"SOT"
BOM_COST"MIO_BIOS_MEM"
SEC"1"
CDS_LOCATION"U2T2"
ROOM"SB_BMC_SPI_MUX"
POWER_GROUP"VCC=P3V3_STBY;GND=GND"
LOCATION"U2T2"
PART_NUMBER"E60229-001"
VALUE"74LVC1G32"
MATERIAL"IC";
"A"
$PN"1"32;
"Y"
$PN"4"50;
"B"
$PN"2"31;
%"RES"
"1","(-1450,1875)","0","mstr_discrete","I101";
;
CDS_SEC"1"
SEC_TYPE"0402"
CDS_LIB"mstr_discrete"
BOM_COST"MIO_BIOS_MEM"
SEC"1"
CDS_LOCATION"R2T13"
ROOM"SB_BMC_SPI_MUX"
LOCATION"R2T13"
PART_NUMBER"G21796-004"
VALUE"200.0"
TOLERANCE"1%"
PACK_TYPE"0402"
MATERIAL"CHIP"
WATTAGE"1/16W";
"B"
$PN"2"52;
"A"
$PN"1"51;
%"RES"
"2","(-3100,2200)","0","mstr_discrete","I105";
;
CDS_SEC"1"
CDS_LIB"mstr_discrete"
SEC_TYPE"0402"
BOM_COST"MIO_BIOS_MEM"
SEC"1"
CDS_LOCATION"R2T11"
ROOM"SB_BMC_SPI_MUX"
LOCATION"R2T11"
PART_NUMBER"G21796-072"
VALUE"4.75K"
TOLERANCE"1%"
PACK_TYPE"0402"
MATERIAL"CHIP"
WATTAGE"1/16W";
"A"
$PN"1"2;
"B"
$PN"2"46;
%"RES"
"2","(-3775,1750)","2","mstr_discrete","I106";
;
CDS_SEC"1"
CDS_LIB"mstr_discrete"
SEC_TYPE"0402"
BOM_COST"MIO_BIOS_MEM"
SEC"1"
CDS_LOCATION"R2T8"
ROOM"SB_BMC_SPI_MUX"
LOCATION"R2T8"
PART_NUMBER"G21796-016"
VALUE"10.0K"
TOLERANCE"1%"
PACK_TYPE"0402"
MATERIAL"CHIP"
WATTAGE"1/16W";
"A"
$PN"1"3;
"B"
$PN"2"31;
%"GND"
"1","(-3100,1275)","0","mstr_symbols","I109";
;
VOLTAGE"0.0V"
CDS_LIB"mstr_symbols"
SIZE"1B"
BODY_TYPE"PLUMBING"
HDL_POWER"GND";
"A\NAC"1;
%"P3V3_STBY"
"1","(-3100,2450)","0","mstr_symbols","I110";
;
VOLTAGE"3.3V"
SIZE"1B"
CDS_LIB"mstr_symbols"
BODY_TYPE"PLUMBING"
HDL_POWER"P3V3_STBY";
"G\NAC"2;
%"P3V3_STBY"
"1","(-3775,2025)","0","mstr_symbols","I111";
;
VOLTAGE"3.3V"
SIZE"1B"
CDS_LIB"mstr_symbols"
BODY_TYPE"PLUMBING"
HDL_POWER"P3V3_STBY";
"G\NAC"3;
%"RES"
"1","(-6725,3600)","0","mstr_discrete","I119";
;
CDS_LIB"mstr_discrete"
CDS_SEC"1"
$SEC"1"
CDS_LOCATION"R8F6"
ROOM"MIO_BIOS_MEM"
WATTAGE"1/16W"
PART_NUMBER"G21497-005"
VALUE"0.0"
MATERIAL"CHIP"
LOCATION"R8F6"
TOLERANCE"5%"
PACK_TYPE"0402";
"B"
$PN"2"33;
"A"
$PN"1"23;
%"P3V3_STBY"
"1","(-5575,4600)","0","mstr_symbols","I12";
;
VOLTAGE"3.3V"
CDS_LIB"mstr_symbols"
SIZE"1B"
BODY_TYPE"PLUMBING"
HDL_POWER"P3V3_STBY";
"G\NAC"4;
%"FET_N"
"8","(-3100,1575)","0","mstr_discrete","I126";
;
CDS_SEC"1"
PACK_TYPE"SOT23LF"
CDS_LIB"mstr_discrete"
BOM_COST"MIO_BIOS_MEM"
SEC_TYPE"SOT23LF"
SEC"1"
CDS_LOCATION"Q8F1"
ROOM"SB_BMC_SPI_MUX"
LOCATION"Q8F1"
PART_NUMBER"C79254-001"
VALUE"2N7002"
MATERIAL"FET";
"GATE"
$PN"1"32;
"DRN"
$PN"3"46;
"SRC"
$PN"2"1;
%"RES"
"2","(-3400,1750)","2","mstr_discrete","I127";
;
CDS_LIB"mstr_discrete"
BOM_COST"MIO_BIOS_MEM"
CDS_SEC"1"
$SEC"1"
CDS_LOCATION"R2T6"
ROOM"SB_BMC_SPI_MUX"
LOCATION"R2T6"
PART_NUMBER"G21796-072"
VALUE"4.75K"
TOLERANCE"1%"
PACK_TYPE"0402"
MATERIAL"CHIP"
WATTAGE"1/16W";
"A"
$PN"1"11;
"B"
$PN"2"32;
%"RES"
"2","(-6250,2750)","0","mstr_discrete","I128";
;
CDS_SEC"1"
CDS_LIB"mstr_discrete"
BOM_COST"MIO_BIOS_MEM"
SEC_TYPE"0402"
SEC"1"
CDS_LOCATION"R1U6"
ROOM"SB_BMC_BPI_MUX"
LOCATION"R1U6"
PART_NUMBER"G21796-016"
VALUE"10.0K"
TOLERANCE"1%"
PACK_TYPE"0402"
MATERIAL"CHIP"
WATTAGE"1/16W";
"A"
$PN"1"41;
"B"
$PN"2"5;
%"GND"
"1","(-6250,2450)","0","mstr_symbols","I129";
;
VOLTAGE"0.0V"
SIZE"1B"
CDS_LIB"mstr_symbols"
BODY_TYPE"PLUMBING"
HDL_POWER"GND";
"A\NAC"5;
%"GND"
"1","(-5400,4100)","0","mstr_symbols","I13";
;
VOLTAGE"0.0V"
SIZE"1B"
CDS_LIB"mstr_symbols"
BODY_TYPE"PLUMBING"
HDL_POWER"GND";
"A\NAC"6;
%"P3V3_STBY"
"1","(-375,2525)","0","mstr_symbols","I131";
;
VOLTAGE"3.3V"
CDS_LIB"mstr_symbols"
SIZE"1B"
BODY_TYPE"PLUMBING"
HDL_POWER"P3V3_STBY";
"G\NAC"7;
%"CAP_A"
"1","(-375,2225)","0","dev_discrete","I132";
;
ROOM"SB_BMC_SPI_MUX"
CDS_LOCATION"C2T12"
BOM_COST"MIO_BIOS_MEM"
CDS_LIB"dev_discrete"
CDS_SEC"1"
SEC_TYPE"0402V"
SEC"1"
LOCATION"C2T12"
PART_NUMBER"A36096-030"
VALUE"0.1UF"
TOLERANCE"10%"
PACK_TYPE"0402V"
VOLTAGE"16V"
MATERIAL"X7R";
"B"
$PN"2"8;
"A"
$PN"1"7;
%"GND"
"1","(-375,1925)","0","mstr_symbols","I133";
;
VOLTAGE"0.0V"
CDS_LIB"mstr_symbols"
SIZE"1B"
BODY_TYPE"PLUMBING"
HDL_POWER"GND";
"A\NAC"8;
%"P3V3_STBY"
"1","(-375,1700)","0","mstr_symbols","I134";
;
VOLTAGE"3.3V"
CDS_LIB"mstr_symbols"
SIZE"1B"
BODY_TYPE"PLUMBING"
HDL_POWER"P3V3_STBY";
"G\NAC"9;
%"CAP_A"
"1","(-375,1400)","0","dev_discrete","I135";
;
ROOM"SB_BMC_SPI_MUX"
CDS_LOCATION"C2T8"
BOM_COST"MIO_BIOS_MEM"
CDS_LIB"dev_discrete"
CDS_SEC"1"
SEC_TYPE"0402V"
SEC"1"
LOCATION"C2T8"
PART_NUMBER"A36096-030"
VALUE"0.1UF"
TOLERANCE"10%"
PACK_TYPE"0402V"
VOLTAGE"16V"
MATERIAL"X7R";
"B"
$PN"2"10;
"A"
$PN"1"9;
%"GND"
"1","(-375,1100)","0","mstr_symbols","I136";
;
VOLTAGE"0.0V"
CDS_LIB"mstr_symbols"
SIZE"1B"
BODY_TYPE"PLUMBING"
HDL_POWER"GND";
"A\NAC"10;
%"P3V3_STBY"
"1","(-3400,2025)","0","mstr_symbols","I137";
;
VOLTAGE"3.3V"
SIZE"1B"
CDS_LIB"mstr_symbols"
BODY_TYPE"PLUMBING"
HDL_POWER"P3V3_STBY";
"G\NAC"11;
%"CAP_A"
"1","(-5400,4350)","0","dev_discrete","I14";
;
ROOM"SB_BMC_SPI_MUX"
CDS_LOCATION"C8E18"
BOM_COST"MIO_BIOS_MEM"
CDS_LIB"dev_discrete"
CDS_SEC"1"
SEC_TYPE"0402V"
SEC"1"
LOCATION"C8E18"
PART_NUMBER"A36096-030"
VALUE"0.1UF"
TOLERANCE"10%"
PACK_TYPE"0402V"
VOLTAGE"16V"
MATERIAL"X7R";
"B"
$PN"2"6;
"A"
$PN"1"4;
%"RES"
"1","(-1450,1150)","0","mstr_discrete","I62";
;
CDS_SEC"1"
BOM_COST"MIO_BIOS_MEM"
CDS_LIB"mstr_discrete"
SEC_TYPE"0402"
SEC"1"
CDS_LOCATION"R2T9"
ROOM"SB_BMC_SPI_MUX"
LOCATION"R2T9"
PART_NUMBER"G21796-267"
VALUE"75"
TOLERANCE"1.0%"
PACK_TYPE"0402"
MATERIAL"CHIP"
WATTAGE"1/16W";
"B"
$PN"2"53;
"A"
$PN"1"50;
%"PI3B3257A"
"1","(-5900,3700)","2","mstr_digital","I74";
;
CDS_SEC"1"
PACK_TYPE"TSSOPLF"
BOM_COST"MIO_BIOS_MEM"
SEC_TYPE"TSSOPLF"
CDS_LIB"mstr_digital"
SEC"1"
CDS_LOCATION"U8F1"
ROOM"SB_BMC_SPI_MUX"
LOCATION"U8F1"
PART_NUMBER"E16801-001"
MATERIAL"IC";
"YC"
$PN"9"44;
"YD"
$PN"12"45;
"IC1"
$PN"10"21;
"IC0"
$PN"11"19;
"IB1"
$PN"6"18;
"YA"
$PN"4"42;
"GND"
$PN"8"12;
"EN \B"
$PN"15"13;
"IA0"
$PN"2"25;
"S"
$PN"1"24;
"IB0"
$PN"5"20;
"IA1"
$PN"3"26;
"ID0"
$PN"14"33;
"ID1"
$PN"13"22;
"YB"
$PN"7"43;
"VCC"
$PN"16"4;
%"PI3B3257A"
"1","(-2000,3875)","2","mstr_digital","I75";
;
CDS_SEC"1"
PACK_TYPE"TSSOPLF"
BOM_COST"MIO_BIOS_MEM"
SEC_TYPE"TSSOPLF"
CDS_LIB"mstr_digital"
SEC"1"
CDS_LOCATION"U2T1"
ROOM"SB_BMC_SPI_MUX"
LOCATION"U2T1"
PART_NUMBER"E16801-001"
MATERIAL"IC";
"YC"
$PN"9"30;
"YD"
$PN"12"54;
"IC1"
$PN"10"36;
"IC0"
$PN"11"35;
"IB1"
$PN"6"49;
"YA"
$PN"4"28;
"GND"
$PN"8"17;
"EN \B"
$PN"15"16;
"IA0"
$PN"2"48;
"S"
$PN"1"27;
"IB0"
$PN"5"34;
"IA1"
$PN"3"47;
"ID0"
$PN"14"37;
"ID1"
$PN"13"38;
"YB"
$PN"7"29;
"VCC"
$PN"16"15;
%"GND"
"1","(-5625,3325)","0","mstr_symbols","I85";
;
VOLTAGE"0.0V"
CDS_LIB"mstr_symbols"
SIZE"1B"
BODY_TYPE"PLUMBING"
HDL_POWER"GND";
"A\NAC"12;
%"GND"
"1","(-6175,3325)","0","mstr_symbols","I86";
;
VOLTAGE"0.0V"
CDS_LIB"mstr_symbols"
SIZE"1B"
BODY_TYPE"PLUMBING"
HDL_POWER"GND";
"A\NAC"13;
%"RES"
"1","(-2925,3975)","0","mstr_discrete","I92";
;
CDS_SEC"1"
SEC_TYPE"0402"
CDS_LIB"mstr_discrete"
BOM_COST"MIO_BIOS_MEM"
SEC"1"
CDS_LOCATION"R2T2"
ROOM"SB_BMC_SPI_MUX"
PACK_TYPE"0402"
TOLERANCE"5%"
PART_NUMBER"G21497-005"
VALUE"0.0"
LOCATION"R2T2"
MATERIAL"CHIP"
WATTAGE"1/16W";
"B"
$PN"2"34;
"A"
$PN"1"39;
%"RES"
"1","(-2925,4075)","0","mstr_discrete","I93";
;
CDS_SEC"1"
SEC_TYPE"0402"
CDS_LIB"mstr_discrete"
BOM_COST"MIO_BIOS_MEM"
SEC"1"
CDS_LOCATION"R2R12"
ROOM"SB_BMC_SPI_MUX"
PART_NUMBER"G21497-005"
PACK_TYPE"0402"
LOCATION"R2R12"
VALUE"0.0"
TOLERANCE"5%"
MATERIAL"CHIP"
WATTAGE"1/16W";
"B"
$PN"2"48;
"A"
$PN"1"40;
%"CAP_A"
"1","(-1500,4525)","0","dev_discrete","I94";
;
ROOM"SB_BMC_SPI_MUX"
CDS_LOCATION"C2T1"
BOM_COST"MIO_BIOS_MEM"
CDS_LIB"dev_discrete"
CDS_SEC"1"
SEC_TYPE"0402V"
SEC"1"
LOCATION"C2T1"
PART_NUMBER"A36096-030"
VALUE"0.1UF"
TOLERANCE"10%"
PACK_TYPE"0402V"
VOLTAGE"16V"
MATERIAL"X7R";
"B"
$PN"2"14;
"A"
$PN"1"15;
%"GND"
"1","(-1500,4275)","0","mstr_symbols","I95";
;
VOLTAGE"0.0V"
CDS_LIB"mstr_symbols"
SIZE"1B"
BODY_TYPE"PLUMBING"
HDL_POWER"GND";
"A\NAC"14;
%"P3V3_STBY"
"1","(-1675,4775)","0","mstr_symbols","I96";
;
VOLTAGE"3.3V"
CDS_LIB"mstr_symbols"
SIZE"1B"
BODY_TYPE"PLUMBING"
HDL_POWER"P3V3_STBY";
"G\NAC"15;
%"GND"
"1","(-2275,3500)","0","mstr_symbols","I97";
;
VOLTAGE"0.0V"
CDS_LIB"mstr_symbols"
SIZE"1B"
BODY_TYPE"PLUMBING"
HDL_POWER"GND";
"A\NAC"16;
%"GND"
"1","(-1725,3500)","0","mstr_symbols","I98";
;
VOLTAGE"0.0V"
CDS_LIB"mstr_symbols"
SIZE"1B"
BODY_TYPE"PLUMBING"
HDL_POWER"GND";
"A\NAC"17;
%"TTL1G32_A"
"1","(-2275,1875)","0","mstr_ttl","I99";
;
CDS_SEC"1"
PACK_TYPE"SOT"
BOM_COST"MIO_BIOS_MEM"
SEC_TYPE"SOT"
CDS_LIB"mstr_ttl"
SEC"1"
CDS_LOCATION"U2T3"
ROOM"SB_BMC_SPI_MUX"
POWER_GROUP"VCC=P3V3_STBY;GND=GND"
LOCATION"U2T3"
PART_NUMBER"E60229-001"
VALUE"74LVC1G32"
MATERIAL"IC";
"A"
$PN"1"46;
"Y"
$PN"4"51;
"B"
$PN"2"31;
END.
